(kicad_pcb
	(version 20260206)
	(generator "pcbnew")
	(generator_version "10.0")
	(general
		(thickness 1.6)
		(legacy_teardrops no)
	)
	(paper "A4")
	(title_block
		(title "Wiwynn_Tioga_Pass_MB.brd")
		(comment 1 "Tioga Pass / footprints 1729-1736 of 4770")
	)
	(layers
		(0 "F.Cu" signal "TOP")
		(4 "In1.Cu" signal "L2GND")
		(6 "In2.Cu" signal "L3")
		(8 "In3.Cu" signal "L4GND")
		(10 "In4.Cu" signal "L5")
		(12 "In5.Cu" signal "L6GND")
		(14 "In6.Cu" signal "L7VCC")
		(16 "In7.Cu" signal "L8VCC")
		(18 "In8.Cu" signal "L9GND")
		(20 "In9.Cu" signal "L10")
		(22 "In10.Cu" signal "L11GND")
		(24 "In11.Cu" signal "L12")
		(26 "In12.Cu" signal "L13GND")
		(2 "B.Cu" signal "BOTTOM")
		(9 "F.Adhes" user "F.Adhesive")
		(11 "B.Adhes" user "B.Adhesive")
		(13 "F.Paste" user "Package Geometry/Pastemask Top")
		(15 "B.Paste" user "Package Geometry/Pastemask Bottom")
		(5 "F.SilkS" user "Ref Des/Silkscreen Top")
		(7 "B.SilkS" user "Ref Des/Silkscreen Bottom")
		(1 "F.Mask" user "Board Geometry/Soldermask Top")
		(3 "B.Mask" user "Board Geometry/Soldermask Bottom")
		(17 "Dwgs.User" user "User.Drawings")
		(19 "Cmts.User" user "User.Comments")
		(21 "Eco1.User" user "User.Eco1")
		(23 "Eco2.User" user "User.Eco2")
		(25 "Edge.Cuts" user "Board Geometry/Outline")
		(27 "Margin" user)
		(31 "F.CrtYd" user "Package Geometry/Place Bound Top")
		(29 "B.CrtYd" user "Package Geometry/Place Bound Bottom")
		(35 "F.Fab" user "Ref Des/Assembly Top")
		(33 "B.Fab" user "Ref Des/Assembly Bottom")
	)
	(footprint ""
		(layer "F.Cu")
		(at 205.0288 -50.5714 90)
		(property "Reference" "R4E16"
			(at 0 0 90)
			(layer "F.SilkS")
			(hide yes)
			(effects
				(font
					(size 1.27 1.27)
				)
			)
		)
		(property "Value" ""
			(at 0 0 90)
			(layer "F.Fab")
			(effects
				(font
					(size 1.27 1.27)
				)
			)
		)
		(duplicate_pad_numbers_are_jumpers no)
		(fp_poly
			(pts
				(xy -0.2794 -0.1016) (xy 0.2794 -0.1016) (xy 0.2794 0.9906) (xy -0.2794 0.9906)
			)
			(stroke
				(width 0)
				(type default)
			)
			(fill no)
			(layer "F.CrtYd")
		)
		(fp_line
			(start 0.2794 -0.1016)
			(end -0.2794 -0.1016)
			(stroke
				(width 0.1)
				(type default)
			)
			(layer "F.Fab")
		)
		(fp_line
			(start -0.2794 -0.1016)
			(end -0.2794 0.9906)
			(stroke
				(width 0.1)
				(type default)
			)
			(layer "F.Fab")
		)
		(fp_line
			(start 0.2794 0.9906)
			(end 0.2794 -0.1016)
			(stroke
				(width 0.1)
				(type default)
			)
			(layer "F.Fab")
		)
		(fp_line
			(start -0.2794 0.9906)
			(end 0.2794 0.9906)
			(stroke
				(width 0.1)
				(type default)
			)
			(layer "F.Fab")
		)
		(pad "1" smd rect
			(at 0 0 90)
			(size 0.508 0.508)
			(layers "F.Cu" "F.Mask" "F.Paste")
			(net "VSENSE_PVCCIN_CPU0_P")
		)
		(pad "2" smd rect
			(at 0 0.889 90)
			(size 0.508 0.508)
			(layers "F.Cu" "F.Mask" "F.Paste")
			(net "VSENSE_PVCCIN_CPU0_SKT_VSEN")
		)
		(zone
			(layer "F.Cu")
			(hatch none 0.5)
			(connect_pads
				(clearance 0)
			)
			(min_thickness 0.25)
			(keepout
				(tracks allowed)
				(vias not_allowed)
				(pads allowed)
				(copperpour not_allowed)
				(footprints allowed)
			)
			(placement
				(enabled no)
				(sheetname "")
			)
			(fill
				(thermal_gap 0.5)
				(thermal_bridge_width 0.5)
				(island_removal_mode 0)
			)
			(polygon
				(pts
					(xy 205.2828 -50.3174) (xy 205.2828 -50.8254) (xy 205.6638 -50.8254) (xy 205.6638 -50.3174)
				)
			)
		)
		(zone
			(layer "F.Cu")
			(hatch none 0.5)
			(connect_pads
				(clearance 0)
			)
			(min_thickness 0.25)
			(keepout
				(tracks not_allowed)
				(vias allowed)
				(pads allowed)
				(copperpour not_allowed)
				(footprints allowed)
			)
			(placement
				(enabled no)
				(sheetname "")
			)
			(fill
				(thermal_gap 0.5)
				(thermal_bridge_width 0.5)
				(island_removal_mode 0)
			)
			(polygon
				(pts
					(xy 205.6638 -50.3174) (xy 205.6638 -50.8254) (xy 205.2828 -50.8254) (xy 205.2828 -50.3174)
				)
			)
		)
	)
	(footprint ""
		(layer "F.Cu")
		(at 348.4118 -157.2768 -90)
		(property "Reference" "C7A17"
			(at 0 0 270)
			(layer "F.SilkS")
			(hide yes)
			(effects
				(font
					(size 1.27 1.27)
				)
			)
		)
		(property "Value" ""
			(at 0 0 270)
			(layer "F.Fab")
			(effects
				(font
					(size 1.27 1.27)
				)
			)
		)
		(duplicate_pad_numbers_are_jumpers no)
		(fp_poly
			(pts
				(xy 0.3048 -0.1016) (xy 0.3048 0.9906) (xy -0.3048 0.9906) (xy -0.3048 -0.1016)
			)
			(stroke
				(width 0)
				(type default)
			)
			(fill no)
			(layer "F.CrtYd")
		)
		(fp_line
			(start -0.3048 0.9906)
			(end 0.3048 0.9906)
			(stroke
				(width 0.1)
				(type default)
			)
			(layer "F.Fab")
		)
		(fp_line
			(start 0.3048 0.9906)
			(end 0.3048 -0.1016)
			(stroke
				(width 0.1)
				(type default)
			)
			(layer "F.Fab")
		)
		(fp_line
			(start -0.3048 -0.1016)
			(end -0.3048 0.9906)
			(stroke
				(width 0.1)
				(type default)
			)
			(layer "F.Fab")
		)
		(fp_line
			(start 0.3048 -0.1016)
			(end -0.3048 -0.1016)
			(stroke
				(width 0.1)
				(type default)
			)
			(layer "F.Fab")
		)
		(pad "1" smd rect
			(at 0 0 270)
			(size 0.508 0.508)
			(layers "F.Cu" "F.Mask" "F.Paste")
			(net "P5V_STBY")
		)
		(pad "2" smd rect
			(at 0 0.889 270)
			(size 0.508 0.508)
			(layers "F.Cu" "F.Mask" "F.Paste")
			(net "GND")
		)
		(zone
			(layer "F.Cu")
			(hatch none 0.5)
			(connect_pads
				(clearance 0)
			)
			(min_thickness 0.25)
			(keepout
				(tracks not_allowed)
				(vias allowed)
				(pads allowed)
				(copperpour not_allowed)
				(footprints allowed)
			)
			(placement
				(enabled no)
				(sheetname "")
			)
			(fill
				(thermal_gap 0.5)
				(thermal_bridge_width 0.5)
				(island_removal_mode 0)
			)
			(polygon
				(pts
					(xy 347.7768 -157.5308) (xy 347.7768 -157.0228) (xy 348.1578 -157.0228) (xy 348.1578 -157.5308)
				)
			)
		)
		(zone
			(layer "F.Cu")
			(hatch none 0.5)
			(connect_pads
				(clearance 0)
			)
			(min_thickness 0.25)
			(keepout
				(tracks allowed)
				(vias not_allowed)
				(pads allowed)
				(copperpour not_allowed)
				(footprints allowed)
			)
			(placement
				(enabled no)
				(sheetname "")
			)
			(fill
				(thermal_gap 0.5)
				(thermal_bridge_width 0.5)
				(island_removal_mode 0)
			)
			(polygon
				(pts
					(xy 348.1578 -157.5308) (xy 348.1578 -157.0228) (xy 347.7768 -157.0228) (xy 347.7768 -157.5308)
				)
			)
		)
	)
	(footprint ""
		(layer "F.Cu")
		(at 412.877 -22.9235)
		(property "Reference" "R25W57"
			(at -0.8382 -0.67818 0)
			(unlocked yes)
			(layer "F.SilkS")
			(effects
				(font
					(size 0.4064 0.254)
					(thickness 0.1524)
				)
				(justify left)
			)
		)
		(property "Value" ""
			(at 0 0 0)
			(layer "F.Fab")
			(effects
				(font
					(size 1.27 1.27)
				)
			)
		)
		(duplicate_pad_numbers_are_jumpers no)
		(fp_poly
			(pts
				(xy -0.2794 -0.1016) (xy 0.2794 -0.1016) (xy 0.2794 0.9906) (xy -0.2794 0.9906)
			)
			(stroke
				(width 0)
				(type default)
			)
			(fill no)
			(layer "F.CrtYd")
		)
		(fp_line
			(start -0.2794 -0.1016)
			(end -0.2794 0.9906)
			(stroke
				(width 0.1)
				(type default)
			)
			(layer "F.Fab")
		)
		(fp_line
			(start -0.2794 0.9906)
			(end 0.2794 0.9906)
			(stroke
				(width 0.1)
				(type default)
			)
			(layer "F.Fab")
		)
		(fp_line
			(start 0.2794 -0.1016)
			(end -0.2794 -0.1016)
			(stroke
				(width 0.1)
				(type default)
			)
			(layer "F.Fab")
		)
		(fp_line
			(start 0.2794 0.9906)
			(end 0.2794 -0.1016)
			(stroke
				(width 0.1)
				(type default)
			)
			(layer "F.Fab")
		)
		(pad "1" smd rect
			(at 0 0)
			(size 0.508 0.508)
			(layers "F.Cu" "F.Mask" "F.Paste")
			(net "PD_ADCREXT")
		)
		(pad "2" smd rect
			(at 0 0.889)
			(size 0.508 0.508)
			(layers "F.Cu" "F.Mask" "F.Paste")
			(net "GND")
		)
		(zone
			(layer "F.Cu")
			(hatch none 0.5)
			(connect_pads
				(clearance 0)
			)
			(min_thickness 0.25)
			(keepout
				(tracks allowed)
				(vias not_allowed)
				(pads allowed)
				(copperpour not_allowed)
				(footprints allowed)
			)
			(placement
				(enabled no)
				(sheetname "")
			)
			(fill
				(thermal_gap 0.5)
				(thermal_bridge_width 0.5)
				(island_removal_mode 0)
			)
			(polygon
				(pts
					(xy 412.623 -22.6695) (xy 413.131 -22.6695) (xy 413.131 -22.2885) (xy 412.623 -22.2885)
				)
			)
		)
		(zone
			(layer "F.Cu")
			(hatch none 0.5)
			(connect_pads
				(clearance 0)
			)
			(min_thickness 0.25)
			(keepout
				(tracks not_allowed)
				(vias allowed)
				(pads allowed)
				(copperpour not_allowed)
				(footprints allowed)
			)
			(placement
				(enabled no)
				(sheetname "")
			)
			(fill
				(thermal_gap 0.5)
				(thermal_bridge_width 0.5)
				(island_removal_mode 0)
			)
			(polygon
				(pts
					(xy 412.623 -22.2885) (xy 413.131 -22.2885) (xy 413.131 -22.6695) (xy 412.623 -22.6695)
				)
			)
		)
	)
	(footprint ""
		(layer "F.Cu")
		(at 453.3265 -32.131 90)
		(property "Reference" "R9F29"
			(at 0 0 90)
			(layer "F.SilkS")
			(hide yes)
			(effects
				(font
					(size 1.27 1.27)
				)
			)
		)
		(property "Value" ""
			(at 0 0 90)
			(layer "F.Fab")
			(effects
				(font
					(size 1.27 1.27)
				)
			)
		)
		(duplicate_pad_numbers_are_jumpers no)
		(fp_poly
			(pts
				(xy -0.2794 -0.1016) (xy 0.2794 -0.1016) (xy 0.2794 0.9906) (xy -0.2794 0.9906)
			)
			(stroke
				(width 0)
				(type default)
			)
			(fill no)
			(layer "F.CrtYd")
		)
		(fp_line
			(start 0.2794 -0.1016)
			(end -0.2794 -0.1016)
			(stroke
				(width 0.1)
				(type default)
			)
			(layer "F.Fab")
		)
		(fp_line
			(start -0.2794 -0.1016)
			(end -0.2794 0.9906)
			(stroke
				(width 0.1)
				(type default)
			)
			(layer "F.Fab")
		)
		(fp_line
			(start 0.2794 0.9906)
			(end 0.2794 -0.1016)
			(stroke
				(width 0.1)
				(type default)
			)
			(layer "F.Fab")
		)
		(fp_line
			(start -0.2794 0.9906)
			(end 0.2794 0.9906)
			(stroke
				(width 0.1)
				(type default)
			)
			(layer "F.Fab")
		)
		(pad "1" smd rect
			(at 0 0 90)
			(size 0.508 0.508)
			(layers "F.Cu" "F.Mask" "F.Paste")
			(net "P1V2_AUX_BMC")
		)
		(pad "2" smd rect
			(at 0 0.889 90)
			(size 0.508 0.508)
			(layers "F.Cu" "F.Mask" "F.Paste")
			(net "RST_BMC_DDR3_R_N")
		)
		(zone
			(layer "F.Cu")
			(hatch none 0.5)
			(connect_pads
				(clearance 0)
			)
			(min_thickness 0.25)
			(keepout
				(tracks allowed)
				(vias not_allowed)
				(pads allowed)
				(copperpour not_allowed)
				(footprints allowed)
			)
			(placement
				(enabled no)
				(sheetname "")
			)
			(fill
				(thermal_gap 0.5)
				(thermal_bridge_width 0.5)
				(island_removal_mode 0)
			)
			(polygon
				(pts
					(xy 453.5805 -31.877) (xy 453.5805 -32.385) (xy 453.9615 -32.385) (xy 453.9615 -31.877)
				)
			)
		)
		(zone
			(layer "F.Cu")
			(hatch none 0.5)
			(connect_pads
				(clearance 0)
			)
			(min_thickness 0.25)
			(keepout
				(tracks not_allowed)
				(vias allowed)
				(pads allowed)
				(copperpour not_allowed)
				(footprints allowed)
			)
			(placement
				(enabled no)
				(sheetname "")
			)
			(fill
				(thermal_gap 0.5)
				(thermal_bridge_width 0.5)
				(island_removal_mode 0)
			)
			(polygon
				(pts
					(xy 453.9615 -31.877) (xy 453.9615 -32.385) (xy 453.5805 -32.385) (xy 453.5805 -31.877)
				)
			)
		)
	)
	(footprint ""
		(layer "F.Cu")
		(at 279.672034 -77.382116)
		(property "Reference" "C6D7"
			(at 0 0 0)
			(layer "F.SilkS")
			(hide yes)
			(effects
				(font
					(size 1.27 1.27)
				)
			)
		)
		(property "Value" ""
			(at 0 0 0)
			(layer "F.Fab")
			(effects
				(font
					(size 1.27 1.27)
				)
			)
		)
		(duplicate_pad_numbers_are_jumpers no)
		(fp_poly
			(pts
				(xy -0.4953 -0.2032) (xy 0.4953 -0.2032) (xy 0.4953 1.6002) (xy -0.4953 1.6002)
			)
			(stroke
				(width 0)
				(type default)
			)
			(fill no)
			(layer "F.CrtYd")
		)
		(fp_line
			(start -0.4953 -0.2032)
			(end 0.4953 -0.2032)
			(stroke
				(width 0.1)
				(type default)
			)
			(layer "F.Fab")
		)
		(fp_line
			(start -0.4953 1.6002)
			(end -0.4953 -0.2032)
			(stroke
				(width 0.1)
				(type default)
			)
			(layer "F.Fab")
		)
		(fp_line
			(start 0.4953 -0.2032)
			(end 0.4953 1.6002)
			(stroke
				(width 0.1)
				(type default)
			)
			(layer "F.Fab")
		)
		(fp_line
			(start 0.4953 1.6002)
			(end -0.4953 1.6002)
			(stroke
				(width 0.1)
				(type default)
			)
			(layer "F.Fab")
		)
		(pad "1" smd rect
			(at 0 0)
			(size 0.762 0.889)
			(layers "F.Cu" "F.Mask" "F.Paste")
			(net "PVCCIO_CPU0")
		)
		(pad "2" smd rect
			(at 0 1.397)
			(size 0.762 0.889)
			(layers "F.Cu" "F.Mask" "F.Paste")
			(net "GND")
		)
		(zone
			(layer "F.Cu")
			(hatch none 0.5)
			(connect_pads
				(clearance 0)
			)
			(min_thickness 0.25)
			(keepout
				(tracks not_allowed)
				(vias allowed)
				(pads allowed)
				(copperpour not_allowed)
				(footprints allowed)
			)
			(placement
				(enabled no)
				(sheetname "")
			)
			(fill
				(thermal_gap 0.5)
				(thermal_bridge_width 0.5)
				(island_removal_mode 0)
			)
			(polygon
				(pts
					(xy 279.291034 -76.937616) (xy 280.053034 -76.937616) (xy 280.053034 -76.429616) (xy 279.291034 -76.429616)
				)
			)
		)
	)
	(footprint ""
		(layer "F.Cu")
		(at 193.7512 -99.9236 90)
		(property "Reference" "C4C8"
			(at 0 0 90)
			(layer "F.SilkS")
			(hide yes)
			(effects
				(font
					(size 1.27 1.27)
				)
			)
		)
		(property "Value" ""
			(at 0 0 90)
			(layer "F.Fab")
			(effects
				(font
					(size 1.27 1.27)
				)
			)
		)
		(duplicate_pad_numbers_are_jumpers no)
		(fp_rect
			(start -0.3048 0.9906)
			(end 0.3048 -0.1016)
			(stroke
				(width 0)
				(type default)
			)
			(fill no)
			(layer "F.CrtYd")
		)
		(fp_line
			(start 0.3048 -0.1016)
			(end -0.3048 -0.1016)
			(stroke
				(width 0.1)
				(type default)
			)
			(layer "F.Fab")
		)
		(fp_line
			(start -0.3048 -0.1016)
			(end -0.3048 0.9906)
			(stroke
				(width 0.1)
				(type default)
			)
			(layer "F.Fab")
		)
		(fp_line
			(start 0.3048 0.9906)
			(end 0.3048 -0.1016)
			(stroke
				(width 0.1)
				(type default)
			)
			(layer "F.Fab")
		)
		(fp_line
			(start -0.3048 0.9906)
			(end 0.3048 0.9906)
			(stroke
				(width 0.1)
				(type default)
			)
			(layer "F.Fab")
		)
		(pad "1" smd rect
			(at 0 0 90)
			(size 0.508 0.508)
			(layers "F.Cu" "F.Mask" "F.Paste")
			(net "VR_PVSA_CPU0_BOOT")
		)
		(pad "2" smd rect
			(at 0 0.889 90)
			(size 0.508 0.508)
			(layers "F.Cu" "F.Mask" "F.Paste")
			(net "VR_PVSA_CPU0_PHASE")
		)
		(zone
			(layer "F.Cu")
			(hatch none 0.5)
			(connect_pads
				(clearance 0)
			)
			(min_thickness 0.25)
			(keepout
				(tracks not_allowed)
				(vias allowed)
				(pads allowed)
				(copperpour not_allowed)
				(footprints allowed)
			)
			(placement
				(enabled no)
				(sheetname "")
			)
			(fill
				(thermal_gap 0.5)
				(thermal_bridge_width 0.5)
				(island_removal_mode 0)
			)
			(polygon
				(pts
					(xy 194.3862 -99.6696) (xy 194.3862 -100.1776) (xy 194.0052 -100.1776) (xy 194.0052 -99.6696)
				)
			)
		)
		(zone
			(layer "F.Cu")
			(hatch none 0.5)
			(connect_pads
				(clearance 0)
			)
			(min_thickness 0.25)
			(keepout
				(tracks allowed)
				(vias not_allowed)
				(pads allowed)
				(copperpour not_allowed)
				(footprints allowed)
			)
			(placement
				(enabled no)
				(sheetname "")
			)
			(fill
				(thermal_gap 0.5)
				(thermal_bridge_width 0.5)
				(island_removal_mode 0)
			)
			(polygon
				(pts
					(xy 194.3862 -99.6696) (xy 194.3862 -100.1776) (xy 194.0052 -100.1776) (xy 194.0052 -99.6696)
				)
			)
		)
	)
	(footprint ""
		(layer "F.Cu")
		(at 180.594 -146.812)
		(property "Reference" "C4A9"
			(at 0 0 0)
			(layer "F.SilkS")
			(hide yes)
			(effects
				(font
					(size 1.27 1.27)
				)
			)
		)
		(property "Value" ""
			(at 0 0 0)
			(layer "F.Fab")
			(effects
				(font
					(size 1.27 1.27)
				)
			)
		)
		(duplicate_pad_numbers_are_jumpers no)
		(fp_rect
			(start 0.3048 -0.1016)
			(end -0.3048 0.9906)
			(stroke
				(width 0)
				(type default)
			)
			(fill no)
			(layer "F.CrtYd")
		)
		(fp_line
			(start -0.3048 -0.1016)
			(end -0.3048 0.9906)
			(stroke
				(width 0.1)
				(type default)
			)
			(layer "F.Fab")
		)
		(fp_line
			(start -0.3048 0.9906)
			(end 0.3048 0.9906)
			(stroke
				(width 0.1)
				(type default)
			)
			(layer "F.Fab")
		)
		(fp_line
			(start 0.3048 -0.1016)
			(end -0.3048 -0.1016)
			(stroke
				(width 0.1)
				(type default)
			)
			(layer "F.Fab")
		)
		(fp_line
			(start 0.3048 0.9906)
			(end 0.3048 -0.1016)
			(stroke
				(width 0.1)
				(type default)
			)
			(layer "F.Fab")
		)
		(pad "1" smd rect
			(at 0 0)
			(size 0.508 0.508)
			(layers "F.Cu" "F.Mask" "F.Paste")
			(net "VR_PVTT_DEF_VREF")
		)
		(pad "2" smd rect
			(at 0 0.889)
			(size 0.508 0.508)
			(layers "F.Cu" "F.Mask" "F.Paste")
			(net "GND")
		)
		(zone
			(layer "F.Cu")
			(hatch none 0.5)
			(connect_pads
				(clearance 0)
			)
			(min_thickness 0.25)
			(keepout
				(tracks not_allowed)
				(vias allowed)
				(pads allowed)
				(copperpour not_allowed)
				(footprints allowed)
			)
			(placement
				(enabled no)
				(sheetname "")
			)
			(fill
				(thermal_gap 0.5)
				(thermal_bridge_width 0.5)
				(island_removal_mode 0)
			)
			(polygon
				(pts
					(xy 180.848 -146.558) (xy 180.34 -146.558) (xy 180.34 -146.177) (xy 180.848 -146.177)
				)
			)
		)
		(zone
			(layer "F.Cu")
			(hatch none 0.5)
			(connect_pads
				(clearance 0)
			)
			(min_thickness 0.25)
			(keepout
				(tracks allowed)
				(vias not_allowed)
				(pads allowed)
				(copperpour not_allowed)
				(footprints allowed)
			)
			(placement
				(enabled no)
				(sheetname "")
			)
			(fill
				(thermal_gap 0.5)
				(thermal_bridge_width 0.5)
				(island_removal_mode 0)
			)
			(polygon
				(pts
					(xy 180.848 -146.558) (xy 180.34 -146.558) (xy 180.34 -146.177) (xy 180.848 -146.177)
				)
			)
		)
	)
	(footprint ""
		(layer "F.Cu")
		(at 24.257 13.2715 -90)
		(property "Reference" "T1P34"
			(at 0 0 270)
			(layer "F.SilkS")
			(hide yes)
			(effects
				(font
					(size 1.27 1.27)
				)
			)
		)
		(property "Value" "*"
			(at 0 -3.44805 270)
			(unlocked yes)
			(layer "F.Fab")
			(hide yes)
			(effects
				(font
					(size 0.889 0.889)
					(thickness 0.1524)
				)
			)
		)
		(property "Device Type" "TPAD-SE-2P-GP_DISCRET-GA1-TPADA"
			(at 0 -4.97205 270)
			(unlocked yes)
			(layer "F.Fab")
			(hide yes)
			(effects
				(font
					(size 0.889 0.889)
					(thickness 0.1524)
				)
			)
		)
		(duplicate_pad_numbers_are_jumpers no)
		(fp_line
			(start -1.016 2.286)
			(end -1.016 -2.286)
			(stroke
				(width 0.1524)
				(type default)
			)
			(layer "F.SilkS")
		)
		(fp_line
			(start 1.016 2.286)
			(end -1.016 2.286)
			(stroke
				(width 0.1524)
				(type default)
			)
			(layer "F.SilkS")
		)
		(fp_line
			(start -1.016 -2.286)
			(end 1.016 -2.286)
			(stroke
				(width 0.1524)
				(type default)
			)
			(layer "F.SilkS")
		)
		(fp_line
			(start 1.016 -2.286)
			(end 1.016 2.286)
			(stroke
				(width 0.1524)
				(type default)
			)
			(layer "F.SilkS")
		)
		(fp_rect
			(start -1.27 2.54)
			(end 1.27 -2.54)
			(stroke
				(width 0)
				(type default)
			)
			(fill no)
			(layer "F.CrtYd")
		)
		(fp_rect
			(start -1.27 2.54)
			(end 1.27 -2.54)
			(stroke
				(width 0)
				(type default)
			)
			(fill no)
			(layer "F.Fab")
		)
		(pad "1" thru_hole circle
			(at 0 -1.27 270)
			(size 1.524 1.524)
			(drill 0.9144)
			(layers "*.Cu" "*.Mask")
			(remove_unused_layers no)
			(net "L10_50OHM_6INCH")
			(clearance -0.0508)
			(thermal_gap 0.127)
			(padstack
				(mode front_inner_back)
				(layer "Inner"
					(shape circle)
					(size 1.1684 1.1684)
					(clearance 0.127)
				)
				(layer "B.Cu"
					(shape circle)
					(size 1.524 1.524)
					(clearance -0.0508)
				)
			)
		)
		(pad "GND1" thru_hole rect
			(at 0 1.27 270)
			(size 1.524 1.524)
			(drill 0.9144)
			(layers "*.Cu" "*.Mask")
			(remove_unused_layers no)
			(net "GND")
			(clearance -0.0508)
			(thermal_gap 0.127)
			(padstack
				(mode front_inner_back)
				(layer "Inner"
					(shape circle)
					(size 1.1684 1.1684)
					(clearance 0.127)
				)
				(layer "B.Cu"
					(shape rect)
					(size 1.524 1.524)
					(clearance -0.0508)
				)
			)
		)
	)
)
